(kicad_pcb
	(version 20260206)
	(generator "pcbnew")
	(generator_version "10.0")
	(general
		(thickness 1.6)
		(legacy_teardrops no)
	)
	(paper "A4")
	(title_block
		(title "04192023_DAF0TMB3IC0_F0TG_MB_C_brd_V02_OCP.brd")
		(comment 1 "Grand Teton / footprints 1424-1429 of 8354")
	)
	(layers
		(0 "F.Cu" signal "TOP")
		(4 "In1.Cu" signal "GND")
		(6 "In2.Cu" signal "IN1")
		(8 "In3.Cu" signal "GND1")
		(10 "In4.Cu" signal "IN2")
		(12 "In5.Cu" signal "GND2")
		(14 "In6.Cu" signal "IN3")
		(16 "In7.Cu" signal "GND3")
		(18 "In8.Cu" signal "VCC")
		(20 "In9.Cu" signal "VCC1")
		(22 "In10.Cu" signal "GND4")
		(24 "In11.Cu" signal "IN4")
		(26 "In12.Cu" signal "GND5")
		(28 "In13.Cu" signal "IN5")
		(30 "In14.Cu" signal "GND6")
		(32 "In15.Cu" signal "IN6")
		(34 "In16.Cu" signal "GND7")
		(2 "B.Cu" signal "BOTTOM")
		(9 "F.Adhes" user "F.Adhesive")
		(11 "B.Adhes" user "B.Adhesive")
		(13 "F.Paste" user "Package Geometry/Pastemask Top")
		(15 "B.Paste" user "Package Geometry/Pastemask Bottom")
		(5 "F.SilkS" user "Ref Des/Silkscreen Top")
		(7 "B.SilkS" user "Ref Des/Silkscreen Bottom")
		(1 "F.Mask" user "Board Geometry/Soldermask Top")
		(3 "B.Mask" user "Board Geometry/Soldermask Bottom")
		(17 "Dwgs.User" user "User.Drawings")
		(19 "Cmts.User" user "User.Comments")
		(21 "Eco1.User" user "User.Eco1")
		(23 "Eco2.User" user "User.Eco2")
		(25 "Edge.Cuts" user "Board Geometry/Outline")
		(27 "Margin" user)
		(31 "F.CrtYd" user "Package Geometry/Place Bound Top")
		(29 "B.CrtYd" user "Package Geometry/Place Bound Bottom")
		(35 "F.Fab" user "Ref Des/Assembly Top")
		(33 "B.Fab" user "Ref Des/Assembly Bottom")
	)
	(footprint ""
		(layer "F.Cu")
		(at 15.58417 -78.830678)
		(property "Reference" "C1809"
			(at 0 0 0)
			(layer "F.SilkS")
			(hide yes)
			(effects
				(font
					(size 1.27 1.27)
				)
			)
		)
		(property "Value" ""
			(at 0 0 0)
			(layer "F.Fab")
			(effects
				(font
					(size 1.27 1.27)
				)
			)
		)
		(duplicate_pad_numbers_are_jumpers no)
		(fp_line
			(start -0.7874 -0.4064)
			(end 0.7874 -0.4064)
			(stroke
				(width 0.1524)
				(type default)
			)
			(layer "F.SilkS")
		)
		(fp_line
			(start -0.7874 0.4064)
			(end -0.7874 -0.4064)
			(stroke
				(width 0.1524)
				(type default)
			)
			(layer "F.SilkS")
		)
		(fp_line
			(start 0.7874 -0.4064)
			(end 0.7874 0.4064)
			(stroke
				(width 0.1524)
				(type default)
			)
			(layer "F.SilkS")
		)
		(fp_line
			(start 0.7874 0.4064)
			(end -0.7874 0.4064)
			(stroke
				(width 0.1524)
				(type default)
			)
			(layer "F.SilkS")
		)
		(fp_line
			(start -0.67945 -0.305054)
			(end -0.12065 -0.305054)
			(stroke
				(width 0.1)
				(type default)
			)
			(layer "F.Fab")
		)
		(fp_line
			(start -0.67945 0.3048)
			(end -0.67945 -0.305054)
			(stroke
				(width 0.1)
				(type default)
			)
			(layer "F.Fab")
		)
		(fp_line
			(start -0.12065 -0.305054)
			(end -0.12065 -0.2794)
			(stroke
				(width 0.1)
				(type default)
			)
			(layer "F.Fab")
		)
		(fp_line
			(start -0.12065 -0.2794)
			(end 0.12065 -0.2794)
			(stroke
				(width 0.1)
				(type default)
			)
			(layer "F.Fab")
		)
		(fp_line
			(start -0.12065 0.2794)
			(end -0.12065 0.3048)
			(stroke
				(width 0.1)
				(type default)
			)
			(layer "F.Fab")
		)
		(fp_line
			(start -0.12065 0.3048)
			(end -0.67945 0.3048)
			(stroke
				(width 0.1)
				(type default)
			)
			(layer "F.Fab")
		)
		(fp_line
			(start 0.120396 0.2794)
			(end -0.12065 0.2794)
			(stroke
				(width 0.1)
				(type default)
			)
			(layer "F.Fab")
		)
		(fp_line
			(start 0.120396 0.3048)
			(end 0.120396 0.2794)
			(stroke
				(width 0.1)
				(type default)
			)
			(layer "F.Fab")
		)
		(fp_line
			(start 0.12065 -0.3048)
			(end 0.67945 -0.3048)
			(stroke
				(width 0.1)
				(type default)
			)
			(layer "F.Fab")
		)
		(fp_line
			(start 0.12065 -0.2794)
			(end 0.12065 -0.3048)
			(stroke
				(width 0.1)
				(type default)
			)
			(layer "F.Fab")
		)
		(fp_line
			(start 0.67945 -0.3048)
			(end 0.67945 0.3048)
			(stroke
				(width 0.1)
				(type default)
			)
			(layer "F.Fab")
		)
		(fp_line
			(start 0.67945 0.3048)
			(end 0.120396 0.3048)
			(stroke
				(width 0.1)
				(type default)
			)
			(layer "F.Fab")
		)
		(pad "1" smd circle
			(at -0.40005 0)
			(size 0 0)
			(layers "F.Cu" "F.Mask" "F.Paste")
			(net "P3V3_AUX")
		)
		(pad "2" smd circle
			(at 0.40005 0)
			(size 0 0)
			(layers "F.Cu" "F.Mask" "F.Paste")
			(net "GND")
		)
	)
	(footprint ""
		(layer "F.Cu")
		(at 12.786106 -106.30408 -90)
		(property "Reference" "R2789"
			(at 0 0 270)
			(layer "F.SilkS")
			(hide yes)
			(effects
				(font
					(size 1.27 1.27)
				)
			)
		)
		(property "Value" ""
			(at 0 0 270)
			(layer "F.Fab")
			(effects
				(font
					(size 1.27 1.27)
				)
			)
		)
		(duplicate_pad_numbers_are_jumpers no)
		(fp_line
			(start -0.7874 0.4064)
			(end -0.7874 -0.4064)
			(stroke
				(width 0.1524)
				(type default)
			)
			(layer "F.SilkS")
		)
		(fp_line
			(start 0.7874 0.4064)
			(end -0.7874 0.4064)
			(stroke
				(width 0.1524)
				(type default)
			)
			(layer "F.SilkS")
		)
		(fp_line
			(start -0.7874 -0.4064)
			(end 0.7874 -0.4064)
			(stroke
				(width 0.1524)
				(type default)
			)
			(layer "F.SilkS")
		)
		(fp_line
			(start 0.7874 -0.4064)
			(end 0.7874 0.4064)
			(stroke
				(width 0.1524)
				(type default)
			)
			(layer "F.SilkS")
		)
		(fp_line
			(start -0.67945 0.3048)
			(end -0.67945 -0.305054)
			(stroke
				(width 0.1)
				(type default)
			)
			(layer "F.Fab")
		)
		(fp_line
			(start -0.12065 0.3048)
			(end -0.67945 0.3048)
			(stroke
				(width 0.1)
				(type default)
			)
			(layer "F.Fab")
		)
		(fp_line
			(start 0.120396 0.3048)
			(end 0.120396 0.2794)
			(stroke
				(width 0.1)
				(type default)
			)
			(layer "F.Fab")
		)
		(fp_line
			(start 0.67945 0.3048)
			(end 0.120396 0.3048)
			(stroke
				(width 0.1)
				(type default)
			)
			(layer "F.Fab")
		)
		(fp_line
			(start -0.12065 0.2794)
			(end -0.12065 0.3048)
			(stroke
				(width 0.1)
				(type default)
			)
			(layer "F.Fab")
		)
		(fp_line
			(start 0.120396 0.2794)
			(end -0.12065 0.2794)
			(stroke
				(width 0.1)
				(type default)
			)
			(layer "F.Fab")
		)
		(fp_line
			(start -0.12065 -0.2794)
			(end 0.12065 -0.2794)
			(stroke
				(width 0.1)
				(type default)
			)
			(layer "F.Fab")
		)
		(fp_line
			(start 0.12065 -0.2794)
			(end 0.12065 -0.3048)
			(stroke
				(width 0.1)
				(type default)
			)
			(layer "F.Fab")
		)
		(fp_line
			(start 0.12065 -0.3048)
			(end 0.67945 -0.3048)
			(stroke
				(width 0.1)
				(type default)
			)
			(layer "F.Fab")
		)
		(fp_line
			(start 0.67945 -0.3048)
			(end 0.67945 0.3048)
			(stroke
				(width 0.1)
				(type default)
			)
			(layer "F.Fab")
		)
		(fp_line
			(start -0.67945 -0.305054)
			(end -0.12065 -0.305054)
			(stroke
				(width 0.1)
				(type default)
			)
			(layer "F.Fab")
		)
		(fp_line
			(start -0.12065 -0.305054)
			(end -0.12065 -0.2794)
			(stroke
				(width 0.1)
				(type default)
			)
			(layer "F.Fab")
		)
		(pad "1" smd rect
			(at -0.40005 0 90)
			(size 0.4572 0.508)
			(layers "F.Cu" "F.Mask" "F.Paste")
			(net "USB2_HOST_BMC_B_BUF_DN")
		)
		(pad "2" smd rect
			(at 0.40005 0 90)
			(size 0.4572 0.508)
			(layers "F.Cu" "F.Mask" "F.Paste")
			(net "USB2_HUB_BUF_SWB_R_DN")
		)
	)
	(footprint ""
		(layer "F.Cu")
		(at 409.830778 -165.928548 -90)
		(property "Reference" "PC580"
			(at 0 0 270)
			(layer "F.SilkS")
			(hide yes)
			(effects
				(font
					(size 1.27 1.27)
				)
			)
		)
		(property "Value" ""
			(at 0 0 270)
			(layer "F.Fab")
			(effects
				(font
					(size 1.27 1.27)
				)
			)
		)
		(duplicate_pad_numbers_are_jumpers no)
		(fp_line
			(start -0.7874 0.4064)
			(end -0.7874 -0.4064)
			(stroke
				(width 0.1524)
				(type default)
			)
			(layer "F.SilkS")
		)
		(fp_line
			(start -0.289052 0.4064)
			(end -0.7874 0.4064)
			(stroke
				(width 0.1524)
				(type default)
			)
			(layer "F.SilkS")
		)
		(fp_line
			(start 0.7874 0.4064)
			(end 0.447548 0.4064)
			(stroke
				(width 0.1524)
				(type default)
			)
			(layer "F.SilkS")
		)
		(fp_line
			(start -0.7874 -0.4064)
			(end 0.7874 -0.4064)
			(stroke
				(width 0.1524)
				(type default)
			)
			(layer "F.SilkS")
		)
		(fp_line
			(start 0.7874 -0.4064)
			(end 0.7874 0.4064)
			(stroke
				(width 0.1524)
				(type default)
			)
			(layer "F.SilkS")
		)
		(fp_line
			(start -0.67945 0.3048)
			(end -0.67945 -0.305054)
			(stroke
				(width 0.1)
				(type default)
			)
			(layer "F.Fab")
		)
		(fp_line
			(start -0.12065 0.3048)
			(end -0.67945 0.3048)
			(stroke
				(width 0.1)
				(type default)
			)
			(layer "F.Fab")
		)
		(fp_line
			(start 0.120396 0.3048)
			(end 0.120396 0.2794)
			(stroke
				(width 0.1)
				(type default)
			)
			(layer "F.Fab")
		)
		(fp_line
			(start 0.67945 0.3048)
			(end 0.120396 0.3048)
			(stroke
				(width 0.1)
				(type default)
			)
			(layer "F.Fab")
		)
		(fp_line
			(start -0.12065 0.2794)
			(end -0.12065 0.3048)
			(stroke
				(width 0.1)
				(type default)
			)
			(layer "F.Fab")
		)
		(fp_line
			(start 0.120396 0.2794)
			(end -0.12065 0.2794)
			(stroke
				(width 0.1)
				(type default)
			)
			(layer "F.Fab")
		)
		(fp_line
			(start -0.12065 -0.2794)
			(end 0.12065 -0.2794)
			(stroke
				(width 0.1)
				(type default)
			)
			(layer "F.Fab")
		)
		(fp_line
			(start 0.12065 -0.2794)
			(end 0.12065 -0.3048)
			(stroke
				(width 0.1)
				(type default)
			)
			(layer "F.Fab")
		)
		(fp_line
			(start 0.12065 -0.3048)
			(end 0.67945 -0.3048)
			(stroke
				(width 0.1)
				(type default)
			)
			(layer "F.Fab")
		)
		(fp_line
			(start 0.67945 -0.3048)
			(end 0.67945 0.3048)
			(stroke
				(width 0.1)
				(type default)
			)
			(layer "F.Fab")
		)
		(fp_line
			(start -0.67945 -0.305054)
			(end -0.12065 -0.305054)
			(stroke
				(width 0.1)
				(type default)
			)
			(layer "F.Fab")
		)
		(fp_line
			(start -0.12065 -0.305054)
			(end -0.12065 -0.2794)
			(stroke
				(width 0.1)
				(type default)
			)
			(layer "F.Fab")
		)
		(pad "1" smd circle
			(at -0.40005 0 270)
			(size 0 0)
			(layers "F.Cu" "F.Mask" "F.Paste")
			(net "PVDDCR_SOC_P0_VCC2")
		)
		(pad "2" smd circle
			(at 0.40005 0 270)
			(size 0 0)
			(layers "F.Cu" "F.Mask" "F.Paste")
			(net "GND")
		)
	)
	(footprint ""
		(layer "F.Cu")
		(at 120.68175 -24.275796)
		(property "Reference" "R6263"
			(at 0 0 0)
			(layer "F.SilkS")
			(hide yes)
			(effects
				(font
					(size 1.27 1.27)
				)
			)
		)
		(property "Value" ""
			(at 0 0 0)
			(layer "F.Fab")
			(effects
				(font
					(size 1.27 1.27)
				)
			)
		)
		(duplicate_pad_numbers_are_jumpers no)
		(fp_line
			(start -0.7874 -0.4064)
			(end 0.7874 -0.4064)
			(stroke
				(width 0.1524)
				(type default)
			)
			(layer "F.SilkS")
		)
		(fp_line
			(start -0.7874 0.4064)
			(end -0.7874 -0.4064)
			(stroke
				(width 0.1524)
				(type default)
			)
			(layer "F.SilkS")
		)
		(fp_line
			(start 0.7874 -0.4064)
			(end 0.7874 0.4064)
			(stroke
				(width 0.1524)
				(type default)
			)
			(layer "F.SilkS")
		)
		(fp_line
			(start 0.7874 0.4064)
			(end -0.7874 0.4064)
			(stroke
				(width 0.1524)
				(type default)
			)
			(layer "F.SilkS")
		)
		(fp_line
			(start -0.67945 -0.305054)
			(end -0.12065 -0.305054)
			(stroke
				(width 0.1)
				(type default)
			)
			(layer "F.Fab")
		)
		(fp_line
			(start -0.67945 0.3048)
			(end -0.67945 -0.305054)
			(stroke
				(width 0.1)
				(type default)
			)
			(layer "F.Fab")
		)
		(fp_line
			(start -0.12065 -0.305054)
			(end -0.12065 -0.2794)
			(stroke
				(width 0.1)
				(type default)
			)
			(layer "F.Fab")
		)
		(fp_line
			(start -0.12065 -0.2794)
			(end 0.12065 -0.2794)
			(stroke
				(width 0.1)
				(type default)
			)
			(layer "F.Fab")
		)
		(fp_line
			(start -0.12065 0.2794)
			(end -0.12065 0.3048)
			(stroke
				(width 0.1)
				(type default)
			)
			(layer "F.Fab")
		)
		(fp_line
			(start -0.12065 0.3048)
			(end -0.67945 0.3048)
			(stroke
				(width 0.1)
				(type default)
			)
			(layer "F.Fab")
		)
		(fp_line
			(start 0.120396 0.2794)
			(end -0.12065 0.2794)
			(stroke
				(width 0.1)
				(type default)
			)
			(layer "F.Fab")
		)
		(fp_line
			(start 0.120396 0.3048)
			(end 0.120396 0.2794)
			(stroke
				(width 0.1)
				(type default)
			)
			(layer "F.Fab")
		)
		(fp_line
			(start 0.12065 -0.3048)
			(end 0.67945 -0.3048)
			(stroke
				(width 0.1)
				(type default)
			)
			(layer "F.Fab")
		)
		(fp_line
			(start 0.12065 -0.2794)
			(end 0.12065 -0.3048)
			(stroke
				(width 0.1)
				(type default)
			)
			(layer "F.Fab")
		)
		(fp_line
			(start 0.67945 -0.3048)
			(end 0.67945 0.3048)
			(stroke
				(width 0.1)
				(type default)
			)
			(layer "F.Fab")
		)
		(fp_line
			(start 0.67945 0.3048)
			(end 0.120396 0.3048)
			(stroke
				(width 0.1)
				(type default)
			)
			(layer "F.Fab")
		)
		(pad "1" smd circle
			(at -0.40005 0)
			(size 0 0)
			(layers "F.Cu" "F.Mask" "F.Paste")
			(net "USB_HUB2_TI_USB_DP_DN3_MRP_VDD12")
		)
		(pad "2" smd circle
			(at 0.40005 0)
			(size 0 0)
			(layers "F.Cu" "F.Mask" "F.Paste")
			(net "P1V2_CPU0_USB2_DVDD12")
		)
	)
	(footprint ""
		(layer "F.Cu")
		(at 100.052124 -338.205064 90)
		(property "Reference" "PR518"
			(at 0 0 90)
			(layer "F.SilkS")
			(hide yes)
			(effects
				(font
					(size 1.27 1.27)
				)
			)
		)
		(property "Value" ""
			(at 0 0 90)
			(layer "F.Fab")
			(effects
				(font
					(size 1.27 1.27)
				)
			)
		)
		(duplicate_pad_numbers_are_jumpers no)
		(fp_line
			(start 0.7874 -0.4064)
			(end 0.7874 0.4064)
			(stroke
				(width 0.1524)
				(type default)
			)
			(layer "F.SilkS")
		)
		(fp_line
			(start -0.7874 -0.4064)
			(end 0.7874 -0.4064)
			(stroke
				(width 0.1524)
				(type default)
			)
			(layer "F.SilkS")
		)
		(fp_line
			(start 0.7874 0.4064)
			(end -0.7874 0.4064)
			(stroke
				(width 0.1524)
				(type default)
			)
			(layer "F.SilkS")
		)
		(fp_line
			(start -0.7874 0.4064)
			(end -0.7874 -0.4064)
			(stroke
				(width 0.1524)
				(type default)
			)
			(layer "F.SilkS")
		)
		(fp_line
			(start -0.12065 -0.305054)
			(end -0.12065 -0.2794)
			(stroke
				(width 0.1)
				(type default)
			)
			(layer "F.Fab")
		)
		(fp_line
			(start -0.67945 -0.305054)
			(end -0.12065 -0.305054)
			(stroke
				(width 0.1)
				(type default)
			)
			(layer "F.Fab")
		)
		(fp_line
			(start 0.67945 -0.3048)
			(end 0.67945 0.3048)
			(stroke
				(width 0.1)
				(type default)
			)
			(layer "F.Fab")
		)
		(fp_line
			(start 0.12065 -0.3048)
			(end 0.67945 -0.3048)
			(stroke
				(width 0.1)
				(type default)
			)
			(layer "F.Fab")
		)
		(fp_line
			(start 0.12065 -0.2794)
			(end 0.12065 -0.3048)
			(stroke
				(width 0.1)
				(type default)
			)
			(layer "F.Fab")
		)
		(fp_line
			(start -0.12065 -0.2794)
			(end 0.12065 -0.2794)
			(stroke
				(width 0.1)
				(type default)
			)
			(layer "F.Fab")
		)
		(fp_line
			(start 0.120396 0.2794)
			(end -0.12065 0.2794)
			(stroke
				(width 0.1)
				(type default)
			)
			(layer "F.Fab")
		)
		(fp_line
			(start -0.12065 0.2794)
			(end -0.12065 0.3048)
			(stroke
				(width 0.1)
				(type default)
			)
			(layer "F.Fab")
		)
		(fp_line
			(start 0.67945 0.3048)
			(end 0.120396 0.3048)
			(stroke
				(width 0.1)
				(type default)
			)
			(layer "F.Fab")
		)
		(fp_line
			(start 0.120396 0.3048)
			(end 0.120396 0.2794)
			(stroke
				(width 0.1)
				(type default)
			)
			(layer "F.Fab")
		)
		(fp_line
			(start -0.12065 0.3048)
			(end -0.67945 0.3048)
			(stroke
				(width 0.1)
				(type default)
			)
			(layer "F.Fab")
		)
		(fp_line
			(start -0.67945 0.3048)
			(end -0.67945 -0.305054)
			(stroke
				(width 0.1)
				(type default)
			)
			(layer "F.Fab")
		)
		(pad "1" smd circle
			(at -0.40005 0 90)
			(size 0 0)
			(layers "F.Cu" "F.Mask" "F.Paste")
			(net "SW_PVDDCR_CPU1_P1_SW6_RC")
		)
		(pad "2" smd circle
			(at 0.40005 0 90)
			(size 0 0)
			(layers "F.Cu" "F.Mask" "F.Paste")
			(net "GND")
		)
	)
	(footprint ""
		(layer "F.Cu")
		(at 204.978 -99.695 180)
		(property "Reference" "R8083"
			(at 0 0 180)
			(layer "F.SilkS")
			(hide yes)
			(effects
				(font
					(size 1.27 1.27)
				)
			)
		)
		(property "Value" ""
			(at 0 0 180)
			(layer "F.Fab")
			(effects
				(font
					(size 1.27 1.27)
				)
			)
		)
		(duplicate_pad_numbers_are_jumpers no)
		(fp_line
			(start 0.7874 0.4064)
			(end -0.7874 0.4064)
			(stroke
				(width 0.1524)
				(type default)
			)
			(layer "F.SilkS")
		)
		(fp_line
			(start 0.7874 -0.4064)
			(end 0.7874 0.4064)
			(stroke
				(width 0.1524)
				(type default)
			)
			(layer "F.SilkS")
		)
		(fp_line
			(start -0.7874 0.4064)
			(end -0.7874 -0.4064)
			(stroke
				(width 0.1524)
				(type default)
			)
			(layer "F.SilkS")
		)
		(fp_line
			(start -0.7874 -0.4064)
			(end 0.7874 -0.4064)
			(stroke
				(width 0.1524)
				(type default)
			)
			(layer "F.SilkS")
		)
		(fp_line
			(start 0.67945 0.3048)
			(end 0.120396 0.3048)
			(stroke
				(width 0.1)
				(type default)
			)
			(layer "F.Fab")
		)
		(fp_line
			(start 0.67945 -0.3048)
			(end 0.67945 0.3048)
			(stroke
				(width 0.1)
				(type default)
			)
			(layer "F.Fab")
		)
		(fp_line
			(start 0.12065 -0.2794)
			(end 0.12065 -0.3048)
			(stroke
				(width 0.1)
				(type default)
			)
			(layer "F.Fab")
		)
		(fp_line
			(start 0.12065 -0.3048)
			(end 0.67945 -0.3048)
			(stroke
				(width 0.1)
				(type default)
			)
			(layer "F.Fab")
		)
		(fp_line
			(start 0.120396 0.3048)
			(end 0.120396 0.2794)
			(stroke
				(width 0.1)
				(type default)
			)
			(layer "F.Fab")
		)
		(fp_line
			(start 0.120396 0.2794)
			(end -0.12065 0.2794)
			(stroke
				(width 0.1)
				(type default)
			)
			(layer "F.Fab")
		)
		(fp_line
			(start -0.12065 0.3048)
			(end -0.67945 0.3048)
			(stroke
				(width 0.1)
				(type default)
			)
			(layer "F.Fab")
		)
		(fp_line
			(start -0.12065 0.2794)
			(end -0.12065 0.3048)
			(stroke
				(width 0.1)
				(type default)
			)
			(layer "F.Fab")
		)
		(fp_line
			(start -0.12065 -0.2794)
			(end 0.12065 -0.2794)
			(stroke
				(width 0.1)
				(type default)
			)
			(layer "F.Fab")
		)
		(fp_line
			(start -0.12065 -0.305054)
			(end -0.12065 -0.2794)
			(stroke
				(width 0.1)
				(type default)
			)
			(layer "F.Fab")
		)
		(fp_line
			(start -0.67945 0.3048)
			(end -0.67945 -0.305054)
			(stroke
				(width 0.1)
				(type default)
			)
			(layer "F.Fab")
		)
		(fp_line
			(start -0.67945 -0.305054)
			(end -0.12065 -0.305054)
			(stroke
				(width 0.1)
				(type default)
			)
			(layer "F.Fab")
		)
		(pad "1" smd circle
			(at -0.40005 0 180)
			(size 0 0)
			(layers "F.Cu" "F.Mask" "F.Paste")
			(net "PWRGD_CHGL_CPU0")
		)
		(pad "2" smd circle
			(at 0.40005 0 180)
			(size 0 0)
			(layers "F.Cu" "F.Mask" "F.Paste")
			(net "PWRGD_CHGL_CPU0_R1")
		)
	)
)
